FILE_TYPE = MACRO_DRAWING;
SET COLOR_WIRE YELLOW;
SET COLOR_PROP ORANGE;
SET COLOR_DOT WHITE;
SET COLOR_ARC YELLOW;
SET COLOR_BODY GREEN;
SET COLOR_NOTE PURPLE;
SET PROP_DISPLAY VALUE;
SET PAGE_NUMBER P120;
FORCEADD OFFPAGE..2
(-500 2525);
FORCEPROP 2 LAST $XR1 120 
J 0
(-221 2525);
DISPLAY 0.638298 (-221 2525);
PAINT MONO (-221 2525);
FORCEPROP 2 LAST $XR0 15 
J 0
(-311 2525);
DISPLAY 0.638298 (-311 2525);
PAINT MONO (-311 2525);
FORCEPROP 2 LAST CDS_LIB standard
J 0
(-500 2525);
DISPLAY INVISIBLE (-500 2525);
FORCEPROP 1 LAST OFFPAGE TRUE
J 0
(-175 2400);
DISPLAY 0.872340 (-175 2400);
PAINT GREEN (-175 2400);
DISPLAY INVISIBLE (-175 2400);
FORCEPROP 1 LAST COMMENT_BODY TRUE
J 0
(-545 2430);
DISPLAY 0.872340 (-545 2430);
PAINT GREEN (-545 2430);
DISPLAY INVISIBLE (-545 2430);
FORCEPROP 2 LAST PATH I11
J 0
(-300 2575);
DISPLAY 1.021277 (-300 2575);
DISPLAY INVISIBLE (-300 2575);
FORCEADD OFFPAGE..2
(-500 2650);
FORCEPROP 2 LAST $XR1 120 
J 0
(-221 2650);
DISPLAY 0.638298 (-221 2650);
PAINT MONO (-221 2650);
FORCEPROP 2 LAST $XR0 15 
J 0
(-311 2650);
DISPLAY 0.638298 (-311 2650);
PAINT MONO (-311 2650);
FORCEPROP 2 LAST CDS_LIB standard
J 0
(-500 2650);
DISPLAY INVISIBLE (-500 2650);
FORCEPROP 1 LAST OFFPAGE TRUE
J 0
(-175 2525);
DISPLAY 0.872340 (-175 2525);
PAINT GREEN (-175 2525);
DISPLAY INVISIBLE (-175 2525);
FORCEPROP 1 LAST COMMENT_BODY TRUE
J 0
(-545 2555);
DISPLAY 0.872340 (-545 2555);
PAINT GREEN (-545 2555);
DISPLAY INVISIBLE (-545 2555);
FORCEPROP 2 LAST PATH I12
J 0
(-300 2700);
DISPLAY 1.021277 (-300 2700);
DISPLAY INVISIBLE (-300 2700);
FORCEADD OFFPAGE..2
(-500 2775);
FORCEPROP 2 LAST $XR0 15 
J 0
(-311 2775);
DISPLAY 0.638298 (-311 2775);
PAINT MONO (-311 2775);
FORCEPROP 2 LAST CDS_LIB standard
J 0
(-500 2775);
DISPLAY INVISIBLE (-500 2775);
FORCEPROP 1 LAST OFFPAGE TRUE
J 0
(-175 2650);
DISPLAY 0.872340 (-175 2650);
PAINT GREEN (-175 2650);
DISPLAY INVISIBLE (-175 2650);
FORCEPROP 1 LAST COMMENT_BODY TRUE
J 0
(-545 2680);
DISPLAY 0.872340 (-545 2680);
PAINT GREEN (-545 2680);
DISPLAY INVISIBLE (-545 2680);
FORCEPROP 2 LAST PATH I14
J 0
(-300 2825);
DISPLAY 1.021277 (-300 2825);
DISPLAY INVISIBLE (-300 2825);
FORCEADD OFFPAGE..2
(-500 2900);
FORCEPROP 2 LAST $XR0 15 
J 0
(-311 2900);
DISPLAY 0.638298 (-311 2900);
PAINT MONO (-311 2900);
FORCEPROP 2 LAST CDS_LIB standard
J 0
(-500 2900);
DISPLAY INVISIBLE (-500 2900);
FORCEPROP 1 LAST OFFPAGE TRUE
J 0
(-175 2775);
DISPLAY 0.872340 (-175 2775);
PAINT GREEN (-175 2775);
DISPLAY INVISIBLE (-175 2775);
FORCEPROP 1 LAST COMMENT_BODY TRUE
J 0
(-545 2805);
DISPLAY 0.872340 (-545 2805);
PAINT GREEN (-545 2805);
DISPLAY INVISIBLE (-545 2805);
FORCEPROP 2 LAST PATH I15
J 0
(-300 2950);
DISPLAY 1.021277 (-300 2950);
DISPLAY INVISIBLE (-300 2950);
FORCEADD OFFPAGE..2
(-500 3275);
FORCEPROP 2 LAST $XR0 15 
J 0
(-311 3275);
DISPLAY 0.638298 (-311 3275);
PAINT MONO (-311 3275);
FORCEPROP 2 LAST CDS_LIB standard
J 0
(-500 3275);
DISPLAY INVISIBLE (-500 3275);
FORCEPROP 1 LAST OFFPAGE TRUE
J 0
(-175 3150);
DISPLAY 0.872340 (-175 3150);
PAINT GREEN (-175 3150);
DISPLAY INVISIBLE (-175 3150);
FORCEPROP 1 LAST COMMENT_BODY TRUE
J 0
(-545 3180);
DISPLAY 0.872340 (-545 3180);
PAINT GREEN (-545 3180);
DISPLAY INVISIBLE (-545 3180);
FORCEPROP 2 LAST PATH I16
J 0
(-300 3325);
DISPLAY 1.021277 (-300 3325);
DISPLAY INVISIBLE (-300 3325);
FORCEADD OFFPAGE..2
(-500 3400);
FORCEPROP 2 LAST $XR0 15 
J 0
(-311 3400);
DISPLAY 0.638298 (-311 3400);
PAINT MONO (-311 3400);
FORCEPROP 2 LAST CDS_LIB standard
J 0
(-500 3400);
DISPLAY INVISIBLE (-500 3400);
FORCEPROP 1 LAST OFFPAGE TRUE
J 0
(-175 3275);
DISPLAY 0.872340 (-175 3275);
PAINT GREEN (-175 3275);
DISPLAY INVISIBLE (-175 3275);
FORCEPROP 1 LAST COMMENT_BODY TRUE
J 0
(-545 3305);
DISPLAY 0.872340 (-545 3305);
PAINT GREEN (-545 3305);
DISPLAY INVISIBLE (-545 3305);
FORCEPROP 2 LAST PATH I17
J 0
(-300 3450);
DISPLAY 1.021277 (-300 3450);
DISPLAY INVISIBLE (-300 3450);
FORCEADD Q_RES..1
(-2000 3400);
FORCEPROP 1 LAST PART_NUMBER CS12402FB01
J 0
(-2100 3450);
DISPLAY 0.510638 (-2100 3450);
DISPLAY INVISIBLE (-2100 3450);
FORCEPROP 1 LAST MATERIAL EMPTY
J 0
(-1650 3400);
DISPLAY 0.638298 (-1650 3400);
PAINT RED (-1650 3400);
FORCEPROP 1 LAST PACK_TYPE 0402LF
J 0
(-2100 3475);
DISPLAY 0.510638 (-2100 3475);
FORCEPROP 1 LAST WATTAGE 1/16W
J 2
(-1800 3475);
DISPLAY 0.510638 (-1800 3475);
FORCEPROP 1 LAST VALUE 240
J 2
(-1825 3400);
DISPLAY 0.638298 (-1825 3400);
FORCEPROP 1 LAST TOLERANCE 1%
J 0
(-1800 3400);
DISPLAY 0.638298 (-1800 3400);
FORCEPROP 1 LAST $LOCATION R249
J 0
(-2225 3400);
DISPLAY 0.808511 (-2225 3400);
FORCEPROP 1 LASTPIN (-2100 3400) $PN 1
J 0
(-2088 3412);
DISPLAY 0.787234 (-2088 3412);
FORCEPROP 1 LASTPIN (-1900 3400) $PN 2
J 0
(-1938 3412);
DISPLAY 0.787234 (-1938 3412);
FORCEPROP 2 LAST CDS_LIB pure_quanta
J 0
(-2000 3400);
PAINT MONO (-2000 3400);
DISPLAY INVISIBLE (-2000 3400);
FORCEPROP 1 LAST PATH I27
J 0
(-2050 3550);
DISPLAY 0.978723 (-2050 3550);
PAINT WHITE (-2050 3550);
DISPLAY INVISIBLE (-2050 3550);
FORCEPROP 2 LAST CDS_LOCATION R249
J 0
(-2050 3600);
DISPLAY 1.021277 (-2050 3600);
DISPLAY INVISIBLE (-2050 3600);
FORCEPROP 2 LAST $SEC 1
J 0
(-2050 3600);
DISPLAY 0.680851 (-2050 3600);
PAINT MONO (-2050 3600);
DISPLAY INVISIBLE (-2050 3600);
FORCEPROP 2 LAST CDS_SEC 1
J 0
(-2050 3600);
DISPLAY 1.021277 (-2050 3600);
DISPLAY INVISIBLE (-2050 3600);
FORCEADD Q_RES..1
(-2000 2900);
FORCEPROP 1 LAST PART_NUMBER CS12402FB01
J 0
(-2100 2950);
DISPLAY 0.510638 (-2100 2950);
DISPLAY INVISIBLE (-2100 2950);
FORCEPROP 1 LAST MATERIAL EMPTY
J 0
(-1700 2900);
DISPLAY 0.638298 (-1700 2900);
PAINT RED (-1700 2900);
FORCEPROP 1 LAST TOLERANCE 1%
J 0
(-1800 2900);
DISPLAY 0.638298 (-1800 2900);
FORCEPROP 1 LAST VALUE 240
J 2
(-1825 2900);
DISPLAY 0.638298 (-1825 2900);
FORCEPROP 1 LAST $LOCATION R251
J 0
(-2225 2900);
DISPLAY 0.787234 (-2225 2900);
FORCEPROP 1 LASTPIN (-2100 2900) $PN 1
J 0
(-2088 2912);
DISPLAY 0.787234 (-2088 2912);
FORCEPROP 1 LASTPIN (-1900 2900) $PN 2
J 0
(-1938 2912);
DISPLAY 0.787234 (-1938 2912);
FORCEPROP 2 LAST CDS_LIB pure_quanta
J 0
(-2000 2900);
PAINT MONO (-2000 2900);
DISPLAY INVISIBLE (-2000 2900);
FORCEPROP 1 LAST PACK_TYPE 0402LF
J 0
(-2100 2975);
DISPLAY 0.510638 (-2100 2975);
DISPLAY INVISIBLE (-2100 2975);
FORCEPROP 1 LAST WATTAGE 1/16W
J 2
(-1800 2975);
DISPLAY 0.510638 (-1800 2975);
DISPLAY INVISIBLE (-1800 2975);
FORCEPROP 1 LAST PATH I28
J 0
(-2050 3050);
DISPLAY 0.978723 (-2050 3050);
PAINT WHITE (-2050 3050);
DISPLAY INVISIBLE (-2050 3050);
FORCEPROP 2 LAST CDS_LOCATION R251
J 0
(-2050 3100);
DISPLAY 1.021277 (-2050 3100);
DISPLAY INVISIBLE (-2050 3100);
FORCEPROP 2 LAST $SEC 1
J 0
(-2050 3100);
DISPLAY 0.680851 (-2050 3100);
PAINT MONO (-2050 3100);
DISPLAY INVISIBLE (-2050 3100);
FORCEPROP 2 LAST CDS_SEC 1
J 0
(-2050 3100);
DISPLAY 1.021277 (-2050 3100);
DISPLAY INVISIBLE (-2050 3100);
FORCEADD Q_RES..1
(-2000 3275);
FORCEPROP 1 LAST PART_NUMBER CS12402FB01
J 0
(-2100 3325);
DISPLAY 0.510638 (-2100 3325);
DISPLAY INVISIBLE (-2100 3325);
FORCEPROP 1 LAST VALUE 240
J 2
(-1825 3275);
DISPLAY 0.638298 (-1825 3275);
FORCEPROP 1 LAST TOLERANCE 1%
J 0
(-1800 3275);
DISPLAY 0.638298 (-1800 3275);
FORCEPROP 1 LAST MATERIAL EMPTY
J 0
(-1650 3275);
DISPLAY 0.638298 (-1650 3275);
PAINT RED (-1650 3275);
FORCEPROP 1 LAST $LOCATION R250
J 0
(-2225 3275);
DISPLAY 0.808511 (-2225 3275);
FORCEPROP 1 LASTPIN (-2100 3275) $PN 1
J 0
(-2088 3287);
DISPLAY 0.787234 (-2088 3287);
FORCEPROP 1 LASTPIN (-1900 3275) $PN 2
J 0
(-1938 3287);
DISPLAY 0.787234 (-1938 3287);
FORCEPROP 1 LAST WATTAGE 1/16W
J 2
(-1800 3350);
DISPLAY 0.510638 (-1800 3350);
DISPLAY INVISIBLE (-1800 3350);
FORCEPROP 1 LAST PACK_TYPE 0402LF
J 0
(-2100 3350);
DISPLAY 0.510638 (-2100 3350);
DISPLAY INVISIBLE (-2100 3350);
FORCEPROP 2 LAST CDS_LIB pure_quanta
J 0
(-2000 3275);
PAINT MONO (-2000 3275);
DISPLAY INVISIBLE (-2000 3275);
FORCEPROP 1 LAST PATH I29
J 0
(-2050 3425);
DISPLAY 0.978723 (-2050 3425);
PAINT WHITE (-2050 3425);
DISPLAY INVISIBLE (-2050 3425);
FORCEPROP 2 LAST CDS_LOCATION R250
J 0
(-2050 3475);
DISPLAY 1.021277 (-2050 3475);
DISPLAY INVISIBLE (-2050 3475);
FORCEPROP 2 LAST $SEC 1
J 0
(-2050 3475);
DISPLAY 0.680851 (-2050 3475);
PAINT MONO (-2050 3475);
DISPLAY INVISIBLE (-2050 3475);
FORCEPROP 2 LAST CDS_SEC 1
J 0
(-2050 3475);
DISPLAY 1.021277 (-2050 3475);
DISPLAY INVISIBLE (-2050 3475);
FORCEADD Q_RES..1
(-2000 2775);
FORCEPROP 1 LAST PART_NUMBER CS12402FB01
J 0
(-2100 2825);
DISPLAY 0.510638 (-2100 2825);
DISPLAY INVISIBLE (-2100 2825);
FORCEPROP 1 LAST VALUE 240
J 2
(-1825 2775);
DISPLAY 0.638298 (-1825 2775);
FORCEPROP 1 LAST TOLERANCE 1%
J 0
(-1800 2775);
DISPLAY 0.638298 (-1800 2775);
FORCEPROP 1 LAST MATERIAL CHIP
J 0
(-1700 2775);
DISPLAY 0.638298 (-1700 2775);
FORCEPROP 1 LAST $LOCATION R252
J 0
(-2225 2775);
DISPLAY 0.787234 (-2225 2775);
FORCEPROP 1 LASTPIN (-2100 2775) $PN 1
J 0
(-2088 2787);
DISPLAY 0.787234 (-2088 2787);
FORCEPROP 1 LASTPIN (-1900 2775) $PN 2
J 0
(-1938 2787);
DISPLAY 0.787234 (-1938 2787);
FORCEPROP 1 LAST WATTAGE 1/16W
J 2
(-1800 2850);
DISPLAY 0.510638 (-1800 2850);
DISPLAY INVISIBLE (-1800 2850);
FORCEPROP 1 LAST PACK_TYPE 0402LF
J 0
(-2100 2850);
DISPLAY 0.510638 (-2100 2850);
DISPLAY INVISIBLE (-2100 2850);
FORCEPROP 2 LAST CDS_LIB pure_quanta
J 0
(-2000 2775);
PAINT MONO (-2000 2775);
DISPLAY INVISIBLE (-2000 2775);
FORCEPROP 1 LAST PATH I30
J 0
(-2050 2925);
DISPLAY 0.978723 (-2050 2925);
PAINT WHITE (-2050 2925);
DISPLAY INVISIBLE (-2050 2925);
FORCEPROP 2 LAST CDS_LOCATION R252
J 0
(-2050 2975);
DISPLAY 1.021277 (-2050 2975);
DISPLAY INVISIBLE (-2050 2975);
FORCEPROP 2 LAST $SEC 1
J 0
(-2050 2975);
DISPLAY 0.680851 (-2050 2975);
PAINT MONO (-2050 2975);
DISPLAY INVISIBLE (-2050 2975);
FORCEPROP 2 LAST CDS_SEC 1
J 0
(-2050 2975);
DISPLAY 1.021277 (-2050 2975);
DISPLAY INVISIBLE (-2050 2975);
FORCEADD Q_RES..1
(-2000 2650);
FORCEPROP 1 LAST PART_NUMBER CS12402FB01
J 0
(-2100 2700);
DISPLAY 0.510638 (-2100 2700);
DISPLAY INVISIBLE (-2100 2700);
FORCEPROP 1 LAST VALUE 240
J 2
(-1825 2650);
DISPLAY 0.638298 (-1825 2650);
FORCEPROP 1 LAST TOLERANCE 1%
J 0
(-1800 2650);
DISPLAY 0.638298 (-1800 2650);
FORCEPROP 1 LAST MATERIAL CHIP
J 0
(-1700 2650);
DISPLAY 0.638298 (-1700 2650);
PAINT RED (-1700 2650);
FORCEPROP 1 LAST $LOCATION R253
J 0
(-2225 2650);
DISPLAY 0.787234 (-2225 2650);
FORCEPROP 1 LASTPIN (-2100 2650) $PN 1
J 0
(-2088 2662);
DISPLAY 0.787234 (-2088 2662);
FORCEPROP 1 LASTPIN (-1900 2650) $PN 2
J 0
(-1938 2662);
DISPLAY 0.787234 (-1938 2662);
FORCEPROP 1 LAST PATH I31
J 0
(-2050 2800);
DISPLAY 0.978723 (-2050 2800);
PAINT WHITE (-2050 2800);
DISPLAY INVISIBLE (-2050 2800);
FORCEPROP 1 LAST PACK_TYPE 0402LF
J 0
(-2100 2725);
DISPLAY 0.510638 (-2100 2725);
DISPLAY INVISIBLE (-2100 2725);
FORCEPROP 1 LAST WATTAGE 1/16W
J 2
(-1800 2725);
DISPLAY 0.510638 (-1800 2725);
DISPLAY INVISIBLE (-1800 2725);
FORCEPROP 2 LAST CDS_LIB pure_quanta
J 0
(-2000 2650);
PAINT MONO (-2000 2650);
DISPLAY INVISIBLE (-2000 2650);
FORCEPROP 2 LAST CDS_LOCATION R253
J 0
(-2050 2850);
DISPLAY 1.021277 (-2050 2850);
DISPLAY INVISIBLE (-2050 2850);
FORCEPROP 2 LAST $SEC 1
J 0
(-2050 2850);
DISPLAY 0.680851 (-2050 2850);
PAINT MONO (-2050 2850);
DISPLAY INVISIBLE (-2050 2850);
FORCEPROP 2 LAST CDS_SEC 1
J 0
(-2050 2850);
DISPLAY 1.021277 (-2050 2850);
DISPLAY INVISIBLE (-2050 2850);
FORCEADD Q_RES..1
(-2000 2525);
FORCEPROP 1 LAST PART_NUMBER CS12402FB01
J 0
(-2100 2575);
DISPLAY 0.510638 (-2100 2575);
DISPLAY INVISIBLE (-2100 2575);
FORCEPROP 1 LAST TOLERANCE 1%
J 0
(-1800 2525);
DISPLAY 0.638298 (-1800 2525);
FORCEPROP 1 LAST VALUE 240
J 2
(-1825 2525);
DISPLAY 0.638298 (-1825 2525);
FORCEPROP 1 LAST MATERIAL CHIP
J 0
(-1700 2525);
DISPLAY 0.638298 (-1700 2525);
PAINT RED (-1700 2525);
FORCEPROP 1 LAST $LOCATION R254
J 0
(-2225 2525);
DISPLAY 0.787234 (-2225 2525);
FORCEPROP 1 LASTPIN (-2100 2525) $PN 1
J 0
(-2088 2537);
DISPLAY 0.787234 (-2088 2537);
FORCEPROP 1 LASTPIN (-1900 2525) $PN 2
J 0
(-1938 2537);
DISPLAY 0.787234 (-1938 2537);
FORCEPROP 1 LAST PATH I32
J 0
(-2050 2675);
DISPLAY 0.978723 (-2050 2675);
PAINT WHITE (-2050 2675);
DISPLAY INVISIBLE (-2050 2675);
FORCEPROP 1 LAST WATTAGE 1/16W
J 2
(-1800 2600);
DISPLAY 0.510638 (-1800 2600);
DISPLAY INVISIBLE (-1800 2600);
FORCEPROP 1 LAST PACK_TYPE 0402LF
J 0
(-2100 2600);
DISPLAY 0.510638 (-2100 2600);
DISPLAY INVISIBLE (-2100 2600);
FORCEPROP 2 LAST CDS_LIB pure_quanta
J 0
(-2000 2525);
PAINT MONO (-2000 2525);
DISPLAY INVISIBLE (-2000 2525);
FORCEPROP 2 LAST CDS_LOCATION R254
J 0
(-2050 2725);
DISPLAY 1.021277 (-2050 2725);
DISPLAY INVISIBLE (-2050 2725);
FORCEPROP 2 LAST $SEC 1
J 0
(-2050 2725);
DISPLAY 0.680851 (-2050 2725);
PAINT MONO (-2050 2725);
DISPLAY INVISIBLE (-2050 2725);
FORCEPROP 2 LAST CDS_SEC 1
J 0
(-2050 2725);
DISPLAY 1.021277 (-2050 2725);
DISPLAY INVISIBLE (-2050 2725);
FORCEADD OFFPAGE..2
(-500 775);
FORCEPROP 2 LAST $XR0 46 
J 0
(-311 775);
DISPLAY 0.638298 (-311 775);
PAINT MONO (-311 775);
FORCEPROP 2 LAST CDS_LIB standard
J 0
(-500 775);
DISPLAY INVISIBLE (-500 775);
FORCEPROP 1 LAST OFFPAGE TRUE
J 0
(-175 650);
DISPLAY 0.872340 (-175 650);
PAINT GREEN (-175 650);
DISPLAY INVISIBLE (-175 650);
FORCEPROP 1 LAST COMMENT_BODY TRUE
J 0
(-545 680);
DISPLAY 0.872340 (-545 680);
PAINT GREEN (-545 680);
DISPLAY INVISIBLE (-545 680);
FORCEPROP 2 LAST PATH I35
J 0
(-300 825);
DISPLAY 1.021277 (-300 825);
DISPLAY INVISIBLE (-300 825);
FORCEADD OFFPAGE..2
(-500 900);
FORCEPROP 2 LAST $XR0 46 
J 0
(-311 900);
DISPLAY 0.638298 (-311 900);
PAINT MONO (-311 900);
FORCEPROP 2 LAST CDS_LIB standard
J 0
(-500 900);
DISPLAY INVISIBLE (-500 900);
FORCEPROP 1 LAST OFFPAGE TRUE
J 0
(-175 775);
DISPLAY 0.872340 (-175 775);
PAINT GREEN (-175 775);
DISPLAY INVISIBLE (-175 775);
FORCEPROP 1 LAST COMMENT_BODY TRUE
J 0
(-545 805);
DISPLAY 0.872340 (-545 805);
PAINT GREEN (-545 805);
DISPLAY INVISIBLE (-545 805);
FORCEPROP 2 LAST PATH I36
J 0
(-300 950);
DISPLAY 1.021277 (-300 950);
DISPLAY INVISIBLE (-300 950);
FORCEADD OFFPAGE..2
(-500 400);
FORCEPROP 2 LAST $XR0 46 
J 0
(-311 400);
DISPLAY 0.638298 (-311 400);
PAINT MONO (-311 400);
FORCEPROP 2 LAST CDS_LIB standard
J 0
(-500 400);
DISPLAY INVISIBLE (-500 400);
FORCEPROP 1 LAST OFFPAGE TRUE
J 0
(-175 275);
DISPLAY 0.872340 (-175 275);
PAINT GREEN (-175 275);
DISPLAY INVISIBLE (-175 275);
FORCEPROP 1 LAST COMMENT_BODY TRUE
J 0
(-545 305);
DISPLAY 0.872340 (-545 305);
PAINT GREEN (-545 305);
DISPLAY INVISIBLE (-545 305);
FORCEPROP 2 LAST PATH I37
J 0
(-300 450);
DISPLAY 1.021277 (-300 450);
DISPLAY INVISIBLE (-300 450);
FORCEADD OFFPAGE..2
(-500 150);
FORCEPROP 2 LAST $XR1 120 
J 0
(-221 150);
DISPLAY 0.638298 (-221 150);
PAINT MONO (-221 150);
FORCEPROP 2 LAST $XR0 46 
J 0
(-311 150);
DISPLAY 0.638298 (-311 150);
PAINT MONO (-311 150);
FORCEPROP 2 LAST CDS_LIB standard
J 0
(-500 150);
DISPLAY INVISIBLE (-500 150);
FORCEPROP 1 LAST OFFPAGE TRUE
J 0
(-175 25);
DISPLAY 0.872340 (-175 25);
PAINT GREEN (-175 25);
DISPLAY INVISIBLE (-175 25);
FORCEPROP 1 LAST COMMENT_BODY TRUE
J 0
(-545 55);
DISPLAY 0.872340 (-545 55);
PAINT GREEN (-545 55);
DISPLAY INVISIBLE (-545 55);
FORCEPROP 2 LAST PATH I38
J 0
(-300 200);
DISPLAY 1.021277 (-300 200);
DISPLAY INVISIBLE (-300 200);
FORCEADD OFFPAGE..2
(-500 275);
FORCEPROP 2 LAST $XR0 46 
J 0
(-311 275);
DISPLAY 0.638298 (-311 275);
PAINT MONO (-311 275);
FORCEPROP 2 LAST CDS_LIB standard
J 0
(-500 275);
DISPLAY INVISIBLE (-500 275);
FORCEPROP 1 LAST OFFPAGE TRUE
J 0
(-175 150);
DISPLAY 0.872340 (-175 150);
PAINT GREEN (-175 150);
DISPLAY INVISIBLE (-175 150);
FORCEPROP 1 LAST COMMENT_BODY TRUE
J 0
(-545 180);
DISPLAY 0.872340 (-545 180);
PAINT GREEN (-545 180);
DISPLAY INVISIBLE (-545 180);
FORCEPROP 2 LAST PATH I39
J 0
(-300 325);
DISPLAY 1.021277 (-300 325);
DISPLAY INVISIBLE (-300 325);
FORCEADD OFFPAGE..2
(-500 25);
FORCEPROP 2 LAST $XR0 46 
J 0
(-311 25);
DISPLAY 0.638298 (-311 25);
PAINT MONO (-311 25);
FORCEPROP 2 LAST $XR1 120 
J 0
(-221 25);
DISPLAY 0.638298 (-221 25);
PAINT MONO (-221 25);
FORCEPROP 2 LAST CDS_LIB standard
J 0
(-500 25);
DISPLAY INVISIBLE (-500 25);
FORCEPROP 1 LAST OFFPAGE TRUE
J 0
(-175 -100);
DISPLAY 0.872340 (-175 -100);
PAINT GREEN (-175 -100);
DISPLAY INVISIBLE (-175 -100);
FORCEPROP 1 LAST COMMENT_BODY TRUE
J 0
(-545 -70);
DISPLAY 0.872340 (-545 -70);
PAINT GREEN (-545 -70);
DISPLAY INVISIBLE (-545 -70);
FORCEPROP 2 LAST PATH I40
J 0
(-300 75);
DISPLAY 1.021277 (-300 75);
DISPLAY INVISIBLE (-300 75);
FORCEADD UNIVERSAL_POWER..1
(-2300 1150);
FORCEPROP 3 LASTPIN (-2300 1100) SIG_NAME PVNN_TERM_CPU1\g
J 0
(-2290 1110);
DISPLAY 0.659574 (-2290 1110);
PAINT MONO (-2290 1110);
DISPLAY INVISIBLE (-2290 1110);
FORCEPROP 1 LAST HDL_POWER PVNN_TERM_CPU1
J 1
(-2300 1200);
DISPLAY 0.872340 (-2300 1200);
PAINT GREEN (-2300 1200);
FORCEPROP 2 LAST CDS_LIB logical_power
J 0
(-2300 1150);
DISPLAY INVISIBLE (-2300 1150);
FORCEPROP 1 LAST PATH I41
J 0
(-2250 1175);
DISPLAY 0.872340 (-2250 1175);
PAINT AQUA (-2250 1175);
DISPLAY INVISIBLE (-2250 1175);
FORCEADD Q_RES..1
(-2000 900);
FORCEPROP 1 LAST PART_NUMBER CS12402FB01
J 0
(-2100 950);
DISPLAY 0.510638 (-2100 950);
DISPLAY INVISIBLE (-2100 950);
FORCEPROP 1 LAST VALUE 240
J 2
(-1825 900);
DISPLAY 0.638298 (-1825 900);
FORCEPROP 1 LAST TOLERANCE 1%
J 0
(-1800 900);
DISPLAY 0.638298 (-1800 900);
FORCEPROP 1 LAST PACK_TYPE 0402LF
J 0
(-2100 975);
DISPLAY 0.510638 (-2100 975);
FORCEPROP 1 LAST WATTAGE 1/16W
J 2
(-1800 975);
DISPLAY 0.510638 (-1800 975);
FORCEPROP 1 LAST MATERIAL EMPTY
J 0
(-1650 900);
DISPLAY 0.638298 (-1650 900);
PAINT RED (-1650 900);
FORCEPROP 1 LAST $LOCATION R255
J 0
(-2225 900);
DISPLAY 0.808511 (-2225 900);
FORCEPROP 1 LASTPIN (-2100 900) $PN 1
J 0
(-2088 912);
DISPLAY 0.787234 (-2088 912);
FORCEPROP 1 LASTPIN (-1900 900) $PN 2
J 0
(-1938 912);
DISPLAY 0.787234 (-1938 912);
FORCEPROP 2 LAST CDS_LIB pure_quanta
J 0
(-2000 900);
PAINT MONO (-2000 900);
DISPLAY INVISIBLE (-2000 900);
FORCEPROP 1 LAST PATH I42
J 0
(-2050 1050);
DISPLAY 0.978723 (-2050 1050);
PAINT WHITE (-2050 1050);
DISPLAY INVISIBLE (-2050 1050);
FORCEPROP 2 LAST CDS_LOCATION R255
J 0
(-2050 1100);
DISPLAY 1.021277 (-2050 1100);
DISPLAY INVISIBLE (-2050 1100);
FORCEPROP 2 LAST $SEC 1
J 0
(-2050 1100);
DISPLAY 0.680851 (-2050 1100);
PAINT MONO (-2050 1100);
DISPLAY INVISIBLE (-2050 1100);
FORCEPROP 2 LAST CDS_SEC 1
J 0
(-2050 1100);
DISPLAY 1.021277 (-2050 1100);
DISPLAY INVISIBLE (-2050 1100);
FORCEADD Q_RES..1
(-2000 400);
FORCEPROP 1 LAST PART_NUMBER CS12402FB01
J 0
(-2100 450);
DISPLAY 0.510638 (-2100 450);
DISPLAY INVISIBLE (-2100 450);
FORCEPROP 1 LAST MATERIAL EMPTY
J 0
(-1700 400);
DISPLAY 0.638298 (-1700 400);
PAINT RED (-1700 400);
FORCEPROP 1 LAST TOLERANCE 1%
J 0
(-1800 400);
DISPLAY 0.638298 (-1800 400);
FORCEPROP 1 LAST VALUE 240
J 2
(-1825 400);
DISPLAY 0.638298 (-1825 400);
FORCEPROP 1 LAST $LOCATION R257
J 0
(-2225 400);
DISPLAY 0.787234 (-2225 400);
FORCEPROP 1 LASTPIN (-2100 400) $PN 1
J 0
(-2088 412);
DISPLAY 0.787234 (-2088 412);
FORCEPROP 1 LASTPIN (-1900 400) $PN 2
J 0
(-1938 412);
DISPLAY 0.787234 (-1938 412);
FORCEPROP 2 LAST CDS_LIB pure_quanta
J 0
(-2000 400);
PAINT MONO (-2000 400);
DISPLAY INVISIBLE (-2000 400);
FORCEPROP 1 LAST WATTAGE 1/16W
J 2
(-1800 475);
DISPLAY 0.510638 (-1800 475);
DISPLAY INVISIBLE (-1800 475);
FORCEPROP 1 LAST PACK_TYPE 0402LF
J 0
(-2100 475);
DISPLAY 0.510638 (-2100 475);
DISPLAY INVISIBLE (-2100 475);
FORCEPROP 1 LAST PATH I43
J 0
(-2050 550);
DISPLAY 0.978723 (-2050 550);
PAINT WHITE (-2050 550);
DISPLAY INVISIBLE (-2050 550);
FORCEPROP 2 LAST CDS_LOCATION R257
J 0
(-2050 600);
DISPLAY 1.021277 (-2050 600);
DISPLAY INVISIBLE (-2050 600);
FORCEPROP 2 LAST $SEC 1
J 0
(-2050 600);
DISPLAY 0.680851 (-2050 600);
PAINT MONO (-2050 600);
DISPLAY INVISIBLE (-2050 600);
FORCEPROP 2 LAST CDS_SEC 1
J 0
(-2050 600);
DISPLAY 1.021277 (-2050 600);
DISPLAY INVISIBLE (-2050 600);
FORCEADD Q_RES..1
(-2000 275);
FORCEPROP 1 LAST PART_NUMBER CS12402FB01
J 0
(-2100 325);
DISPLAY 0.510638 (-2100 325);
DISPLAY INVISIBLE (-2100 325);
FORCEPROP 1 LAST VALUE 240
J 2
(-1825 275);
DISPLAY 0.638298 (-1825 275);
FORCEPROP 1 LAST TOLERANCE 1%
J 0
(-1800 275);
DISPLAY 0.638298 (-1800 275);
FORCEPROP 1 LAST MATERIAL CHIP
J 0
(-1700 275);
DISPLAY 0.638298 (-1700 275);
FORCEPROP 1 LAST $LOCATION R258
J 0
(-2225 275);
DISPLAY 0.787234 (-2225 275);
FORCEPROP 1 LASTPIN (-2100 275) $PN 1
J 0
(-2088 287);
DISPLAY 0.787234 (-2088 287);
FORCEPROP 1 LASTPIN (-1900 275) $PN 2
J 0
(-1938 287);
DISPLAY 0.787234 (-1938 287);
FORCEPROP 1 LAST PACK_TYPE 0402LF
J 0
(-2100 350);
DISPLAY 0.510638 (-2100 350);
DISPLAY INVISIBLE (-2100 350);
FORCEPROP 1 LAST WATTAGE 1/16W
J 2
(-1800 350);
DISPLAY 0.510638 (-1800 350);
DISPLAY INVISIBLE (-1800 350);
FORCEPROP 2 LAST CDS_LIB pure_quanta
J 0
(-2000 275);
PAINT MONO (-2000 275);
DISPLAY INVISIBLE (-2000 275);
FORCEPROP 1 LAST PATH I44
J 0
(-2050 425);
DISPLAY 0.978723 (-2050 425);
PAINT WHITE (-2050 425);
DISPLAY INVISIBLE (-2050 425);
FORCEPROP 2 LAST CDS_LOCATION R258
J 0
(-2050 475);
DISPLAY 1.021277 (-2050 475);
DISPLAY INVISIBLE (-2050 475);
FORCEPROP 2 LAST $SEC 1
J 0
(-2050 475);
DISPLAY 0.680851 (-2050 475);
PAINT MONO (-2050 475);
DISPLAY INVISIBLE (-2050 475);
FORCEPROP 2 LAST CDS_SEC 1
J 0
(-2050 475);
DISPLAY 1.021277 (-2050 475);
DISPLAY INVISIBLE (-2050 475);
FORCEADD Q_RES..1
(-2000 150);
FORCEPROP 1 LAST PART_NUMBER CS12402FB01
J 0
(-2100 200);
DISPLAY 0.510638 (-2100 200);
DISPLAY INVISIBLE (-2100 200);
FORCEPROP 1 LAST VALUE 240
J 2
(-1825 150);
DISPLAY 0.638298 (-1825 150);
FORCEPROP 1 LAST TOLERANCE 1%
J 0
(-1800 150);
DISPLAY 0.638298 (-1800 150);
FORCEPROP 1 LAST MATERIAL CHIP
J 0
(-1700 150);
DISPLAY 0.638298 (-1700 150);
PAINT RED (-1700 150);
FORCEPROP 1 LAST $LOCATION R259
J 0
(-2225 150);
DISPLAY 0.787234 (-2225 150);
FORCEPROP 1 LASTPIN (-2100 150) $PN 1
J 0
(-2088 162);
DISPLAY 0.787234 (-2088 162);
FORCEPROP 1 LASTPIN (-1900 150) $PN 2
J 0
(-1938 162);
DISPLAY 0.787234 (-1938 162);
FORCEPROP 1 LAST PATH I45
J 0
(-2050 300);
DISPLAY 0.978723 (-2050 300);
PAINT WHITE (-2050 300);
DISPLAY INVISIBLE (-2050 300);
FORCEPROP 1 LAST WATTAGE 1/16W
J 2
(-1800 225);
DISPLAY 0.510638 (-1800 225);
DISPLAY INVISIBLE (-1800 225);
FORCEPROP 1 LAST PACK_TYPE 0402LF
J 0
(-2100 225);
DISPLAY 0.510638 (-2100 225);
DISPLAY INVISIBLE (-2100 225);
FORCEPROP 2 LAST CDS_LIB pure_quanta
J 0
(-2000 150);
PAINT MONO (-2000 150);
DISPLAY INVISIBLE (-2000 150);
FORCEPROP 2 LAST CDS_LOCATION R259
J 0
(-2050 350);
DISPLAY 1.021277 (-2050 350);
DISPLAY INVISIBLE (-2050 350);
FORCEPROP 2 LAST $SEC 1
J 0
(-2050 350);
DISPLAY 0.680851 (-2050 350);
PAINT MONO (-2050 350);
DISPLAY INVISIBLE (-2050 350);
FORCEPROP 2 LAST CDS_SEC 1
J 0
(-2050 350);
DISPLAY 1.021277 (-2050 350);
DISPLAY INVISIBLE (-2050 350);
FORCEADD Q_RES..1
(-2000 25);
FORCEPROP 1 LAST PART_NUMBER CS12402FB01
J 0
(-2100 75);
DISPLAY 0.510638 (-2100 75);
DISPLAY INVISIBLE (-2100 75);
FORCEPROP 1 LAST VALUE 240
J 2
(-1825 25);
DISPLAY 0.638298 (-1825 25);
FORCEPROP 1 LAST TOLERANCE 1%
J 0
(-1800 25);
DISPLAY 0.638298 (-1800 25);
FORCEPROP 1 LAST MATERIAL CHIP
J 0
(-1700 25);
DISPLAY 0.638298 (-1700 25);
PAINT RED (-1700 25);
FORCEPROP 1 LAST $LOCATION R260
J 0
(-2225 25);
DISPLAY 0.787234 (-2225 25);
FORCEPROP 1 LASTPIN (-2100 25) $PN 1
J 0
(-2088 37);
DISPLAY 0.787234 (-2088 37);
FORCEPROP 1 LASTPIN (-1900 25) $PN 2
J 0
(-1938 37);
DISPLAY 0.787234 (-1938 37);
FORCEPROP 1 LAST PATH I46
J 0
(-2050 175);
DISPLAY 0.978723 (-2050 175);
PAINT WHITE (-2050 175);
DISPLAY INVISIBLE (-2050 175);
FORCEPROP 1 LAST WATTAGE 1/16W
J 2
(-1800 100);
DISPLAY 0.510638 (-1800 100);
DISPLAY INVISIBLE (-1800 100);
FORCEPROP 1 LAST PACK_TYPE 0402LF
J 0
(-2100 100);
DISPLAY 0.510638 (-2100 100);
DISPLAY INVISIBLE (-2100 100);
FORCEPROP 2 LAST CDS_LIB pure_quanta
J 0
(-2000 25);
PAINT MONO (-2000 25);
DISPLAY INVISIBLE (-2000 25);
FORCEPROP 2 LAST CDS_LOCATION R260
J 0
(-2050 225);
DISPLAY 1.021277 (-2050 225);
DISPLAY INVISIBLE (-2050 225);
FORCEPROP 2 LAST $SEC 1
J 0
(-2050 225);
DISPLAY 0.680851 (-2050 225);
PAINT MONO (-2050 225);
DISPLAY INVISIBLE (-2050 225);
FORCEPROP 2 LAST CDS_SEC 1
J 0
(-2050 225);
DISPLAY 1.021277 (-2050 225);
DISPLAY INVISIBLE (-2050 225);
FORCEADD Q_RES..1
(-2000 775);
FORCEPROP 1 LAST PART_NUMBER CS12402FB01
J 0
(-2100 825);
DISPLAY 0.510638 (-2100 825);
DISPLAY INVISIBLE (-2100 825);
FORCEPROP 1 LAST MATERIAL EMPTY
J 0
(-1650 775);
DISPLAY 0.638298 (-1650 775);
PAINT RED (-1650 775);
FORCEPROP 1 LAST VALUE 240
J 2
(-1825 775);
DISPLAY 0.638298 (-1825 775);
FORCEPROP 1 LAST TOLERANCE 1%
J 0
(-1800 775);
DISPLAY 0.638298 (-1800 775);
FORCEPROP 1 LAST $LOCATION R256
J 0
(-2225 775);
DISPLAY 0.808511 (-2225 775);
FORCEPROP 1 LASTPIN (-2100 775) $PN 1
J 0
(-2088 787);
DISPLAY 0.787234 (-2088 787);
FORCEPROP 1 LASTPIN (-1900 775) $PN 2
J 0
(-1938 787);
DISPLAY 0.787234 (-1938 787);
FORCEPROP 2 LAST CDS_LIB pure_quanta
J 0
(-2000 775);
PAINT MONO (-2000 775);
DISPLAY INVISIBLE (-2000 775);
FORCEPROP 1 LAST PACK_TYPE 0402LF
J 0
(-2100 850);
DISPLAY 0.510638 (-2100 850);
DISPLAY INVISIBLE (-2100 850);
FORCEPROP 1 LAST WATTAGE 1/16W
J 2
(-1800 850);
DISPLAY 0.510638 (-1800 850);
DISPLAY INVISIBLE (-1800 850);
FORCEPROP 1 LAST PATH I48
J 0
(-2050 925);
DISPLAY 0.978723 (-2050 925);
PAINT WHITE (-2050 925);
DISPLAY INVISIBLE (-2050 925);
FORCEPROP 2 LAST CDS_LOCATION R256
J 0
(-2050 975);
DISPLAY 1.021277 (-2050 975);
DISPLAY INVISIBLE (-2050 975);
FORCEPROP 2 LAST $SEC 1
J 0
(-2050 975);
DISPLAY 0.680851 (-2050 975);
PAINT MONO (-2050 975);
DISPLAY INVISIBLE (-2050 975);
FORCEPROP 2 LAST CDS_SEC 1
J 0
(-2050 975);
DISPLAY 1.021277 (-2050 975);
DISPLAY INVISIBLE (-2050 975);
FORCEADD UNIVERSAL_GND..1
(400 2925);
FORCEPROP 3 LASTPIN (400 2975) SIG_NAME GND\g
J 0
(410 2985);
DISPLAY 0.659574 (410 2985);
PAINT MONO (410 2985);
DISPLAY INVISIBLE (410 2985);
FORCEPROP 2 LAST CDS_LIB logical_power
J 0
(400 2925);
PAINT MONO (400 2925);
DISPLAY INVISIBLE (400 2925);
FORCEPROP 1 LAST HDL_POWER GND
J 1
(425 2850);
DISPLAY 0.872340 (425 2850);
PAINT GREEN (425 2850);
DISPLAY INVISIBLE (425 2850);
FORCEPROP 1 LAST PATH I55
J 0
(475 2925);
DISPLAY 0.872340 (475 2925);
PAINT AQUA (475 2925);
DISPLAY INVISIBLE (475 2925);
FORCEADD OFFPAGE..2
(2200 3200);
FORCEPROP 2 LAST $XR1 120 
J 0
(2479 3200);
DISPLAY 0.638298 (2479 3200);
PAINT MONO (2479 3200);
FORCEPROP 2 LAST $XR0 15 
J 0
(2389 3200);
DISPLAY 0.638298 (2389 3200);
PAINT MONO (2389 3200);
FORCEPROP 2 LAST CDS_LIB standard
J 0
(2200 3200);
DISPLAY INVISIBLE (2200 3200);
FORCEPROP 1 LAST OFFPAGE TRUE
J 0
(2525 3075);
DISPLAY 0.872340 (2525 3075);
PAINT GREEN (2525 3075);
DISPLAY INVISIBLE (2525 3075);
FORCEPROP 1 LAST COMMENT_BODY TRUE
J 0
(2155 3105);
DISPLAY 0.872340 (2155 3105);
PAINT GREEN (2155 3105);
DISPLAY INVISIBLE (2155 3105);
FORCEPROP 2 LAST PATH I57
J 0
(2400 3250);
DISPLAY 1.021277 (2400 3250);
DISPLAY INVISIBLE (2400 3250);
FORCEADD OFFPAGE..2
(2200 3075);
FORCEPROP 2 LAST $XR1 120 
J 0
(2479 3075);
DISPLAY 0.638298 (2479 3075);
PAINT MONO (2479 3075);
FORCEPROP 2 LAST $XR0 15 
J 0
(2389 3075);
DISPLAY 0.638298 (2389 3075);
PAINT MONO (2389 3075);
FORCEPROP 2 LAST CDS_LIB standard
J 0
(2200 3075);
DISPLAY INVISIBLE (2200 3075);
FORCEPROP 1 LAST OFFPAGE TRUE
J 0
(2525 2950);
DISPLAY 0.872340 (2525 2950);
PAINT GREEN (2525 2950);
DISPLAY INVISIBLE (2525 2950);
FORCEPROP 1 LAST COMMENT_BODY TRUE
J 0
(2155 2980);
DISPLAY 0.872340 (2155 2980);
PAINT GREEN (2155 2980);
DISPLAY INVISIBLE (2155 2980);
FORCEPROP 2 LAST PATH I58
J 0
(2400 3125);
DISPLAY 1.021277 (2400 3125);
DISPLAY INVISIBLE (2400 3125);
FORCEADD Q_RES..1
(700 3200);
FORCEPROP 1 LAST PART_NUMBER CS12402FB01
J 0
(600 3275);
DISPLAY 0.510638 (600 3275);
DISPLAY INVISIBLE (600 3275);
FORCEPROP 1 LAST TOLERANCE 1%
J 0
(925 3200);
DISPLAY 0.638298 (925 3200);
FORCEPROP 1 LAST VALUE 240
J 2
(900 3200);
DISPLAY 0.638298 (900 3200);
FORCEPROP 1 LAST WATTAGE 1/16W
J 2
(875 3300);
DISPLAY 0.510638 (875 3300);
FORCEPROP 1 LAST MATERIAL EMPTY
J 0
(1025 3200);
DISPLAY 0.638298 (1025 3200);
FORCEPROP 1 LAST PACK_TYPE 0402LF
J 0
(600 3300);
DISPLAY 0.510638 (600 3300);
FORCEPROP 1 LAST $LOCATION R1391
J 0
(475 3200);
DISPLAY 0.638298 (475 3200);
FORCEPROP 1 LASTPIN (600 3200) $PN 1
J 0
(612 3212);
DISPLAY 0.787234 (612 3212);
FORCEPROP 1 LASTPIN (800 3200) $PN 2
J 0
(762 3212);
DISPLAY 0.787234 (762 3212);
FORCEPROP 1 LAST PATH I61
J 0
(650 3350);
DISPLAY 0.978723 (650 3350);
PAINT WHITE (650 3350);
DISPLAY INVISIBLE (650 3350);
FORCEPROP 2 LAST CDS_LIB pure_quanta
J 0
(700 3200);
PAINT MONO (700 3200);
DISPLAY INVISIBLE (700 3200);
FORCEPROP 2 LAST CDS_LOCATION R1391
J 0
(650 3400);
DISPLAY 1.021277 (650 3400);
DISPLAY INVISIBLE (650 3400);
FORCEPROP 2 LAST $SEC 1
J 0
(650 3400);
DISPLAY 0.680851 (650 3400);
PAINT MONO (650 3400);
DISPLAY INVISIBLE (650 3400);
FORCEPROP 2 LAST CDS_SEC 1
J 0
(650 3400);
DISPLAY 1.021277 (650 3400);
DISPLAY INVISIBLE (650 3400);
FORCEADD Q_RES..1
(700 3075);
FORCEPROP 1 LAST PART_NUMBER CS12402FB01
J 0
(600 3150);
DISPLAY 0.510638 (600 3150);
DISPLAY INVISIBLE (600 3150);
FORCEPROP 1 LAST VALUE 240
J 2
(900 3075);
DISPLAY 0.638298 (900 3075);
FORCEPROP 1 LAST MATERIAL EMPTY
J 0
(1025 3075);
DISPLAY 0.638298 (1025 3075);
FORCEPROP 1 LAST TOLERANCE 1%
J 0
(925 3075);
DISPLAY 0.638298 (925 3075);
FORCEPROP 1 LAST $LOCATION R1392
J 0
(475 3075);
DISPLAY 0.638298 (475 3075);
FORCEPROP 1 LASTPIN (600 3075) $PN 1
J 0
(612 3087);
DISPLAY 0.787234 (612 3087);
FORCEPROP 1 LASTPIN (800 3075) $PN 2
J 0
(762 3087);
DISPLAY 0.787234 (762 3087);
FORCEPROP 1 LAST PATH I62
J 0
(650 3225);
DISPLAY 0.978723 (650 3225);
PAINT WHITE (650 3225);
DISPLAY INVISIBLE (650 3225);
FORCEPROP 2 LAST CDS_LIB pure_quanta
J 0
(700 3075);
PAINT MONO (700 3075);
DISPLAY INVISIBLE (700 3075);
FORCEPROP 1 LAST PACK_TYPE 0402LF
J 0
(600 3175);
DISPLAY 0.510638 (600 3175);
DISPLAY INVISIBLE (600 3175);
FORCEPROP 1 LAST WATTAGE 1/16W
J 2
(875 3175);
DISPLAY 0.510638 (875 3175);
DISPLAY INVISIBLE (875 3175);
FORCEPROP 2 LAST CDS_LOCATION R1392
J 0
(650 3275);
DISPLAY 1.021277 (650 3275);
DISPLAY INVISIBLE (650 3275);
FORCEPROP 2 LAST $SEC 1
J 0
(650 3275);
DISPLAY 0.680851 (650 3275);
PAINT MONO (650 3275);
DISPLAY INVISIBLE (650 3275);
FORCEPROP 2 LAST CDS_SEC 1
J 0
(650 3275);
DISPLAY 1.021277 (650 3275);
DISPLAY INVISIBLE (650 3275);
FORCEADD UNIVERSAL_GND..1
(400 475);
FORCEPROP 3 LASTPIN (400 525) SIG_NAME GND\g
J 0
(410 535);
DISPLAY 0.659574 (410 535);
PAINT MONO (410 535);
DISPLAY INVISIBLE (410 535);
FORCEPROP 2 LAST CDS_LIB logical_power
J 0
(400 475);
PAINT MONO (400 475);
DISPLAY INVISIBLE (400 475);
FORCEPROP 1 LAST HDL_POWER GND
J 1
(425 400);
DISPLAY 0.872340 (425 400);
PAINT GREEN (425 400);
DISPLAY INVISIBLE (425 400);
FORCEPROP 1 LAST PATH I63
J 0
(475 475);
DISPLAY 0.872340 (475 475);
PAINT AQUA (475 475);
DISPLAY INVISIBLE (475 475);
FORCEADD OFFPAGE..2
(2200 750);
FORCEPROP 2 LAST $XR1 120 
J 0
(2479 750);
DISPLAY 0.638298 (2479 750);
PAINT MONO (2479 750);
FORCEPROP 2 LAST $XR0 46 
J 0
(2389 750);
DISPLAY 0.638298 (2389 750);
PAINT MONO (2389 750);
FORCEPROP 2 LAST CDS_LIB standard
J 0
(2200 750);
DISPLAY INVISIBLE (2200 750);
FORCEPROP 1 LAST OFFPAGE TRUE
J 0
(2525 625);
DISPLAY 0.872340 (2525 625);
PAINT GREEN (2525 625);
DISPLAY INVISIBLE (2525 625);
FORCEPROP 1 LAST COMMENT_BODY TRUE
J 0
(2155 655);
DISPLAY 0.872340 (2155 655);
PAINT GREEN (2155 655);
DISPLAY INVISIBLE (2155 655);
FORCEPROP 2 LAST PATH I64
J 0
(2400 800);
DISPLAY 1.021277 (2400 800);
DISPLAY INVISIBLE (2400 800);
FORCEADD OFFPAGE..2
(2200 625);
FORCEPROP 2 LAST $XR1 120 
J 0
(2479 625);
DISPLAY 0.638298 (2479 625);
PAINT MONO (2479 625);
FORCEPROP 2 LAST $XR0 46 
J 0
(2389 625);
DISPLAY 0.638298 (2389 625);
PAINT MONO (2389 625);
FORCEPROP 2 LAST CDS_LIB standard
J 0
(2200 625);
DISPLAY INVISIBLE (2200 625);
FORCEPROP 1 LAST OFFPAGE TRUE
J 0
(2525 500);
DISPLAY 0.872340 (2525 500);
PAINT GREEN (2525 500);
DISPLAY INVISIBLE (2525 500);
FORCEPROP 1 LAST COMMENT_BODY TRUE
J 0
(2155 530);
DISPLAY 0.872340 (2155 530);
PAINT GREEN (2155 530);
DISPLAY INVISIBLE (2155 530);
FORCEPROP 2 LAST PATH I65
J 0
(2400 675);
DISPLAY 1.021277 (2400 675);
DISPLAY INVISIBLE (2400 675);
FORCEADD Q_RES..1
(700 750);
FORCEPROP 1 LAST PART_NUMBER CS12402FB01
J 0
(600 825);
DISPLAY 0.510638 (600 825);
DISPLAY INVISIBLE (600 825);
FORCEPROP 1 LAST PACK_TYPE 0402LF
J 0
(600 850);
DISPLAY 0.510638 (600 850);
FORCEPROP 1 LAST TOLERANCE 1%
J 0
(925 750);
DISPLAY 0.638298 (925 750);
FORCEPROP 1 LAST WATTAGE 1/16W
J 2
(875 850);
DISPLAY 0.510638 (875 850);
FORCEPROP 1 LAST VALUE 240
J 2
(900 750);
DISPLAY 0.638298 (900 750);
FORCEPROP 1 LAST MATERIAL EMPTY
J 0
(1025 750);
DISPLAY 0.638298 (1025 750);
FORCEPROP 1 LAST $LOCATION R1393
J 0
(475 750);
DISPLAY 0.638298 (475 750);
FORCEPROP 1 LASTPIN (600 750) $PN 1
J 0
(612 762);
DISPLAY 0.787234 (612 762);
FORCEPROP 1 LASTPIN (800 750) $PN 2
J 0
(762 762);
DISPLAY 0.787234 (762 762);
FORCEPROP 1 LAST PATH I66
J 0
(650 900);
DISPLAY 0.978723 (650 900);
PAINT WHITE (650 900);
DISPLAY INVISIBLE (650 900);
FORCEPROP 2 LAST CDS_LIB pure_quanta
J 0
(700 750);
PAINT MONO (700 750);
DISPLAY INVISIBLE (700 750);
FORCEPROP 2 LAST CDS_LOCATION R1393
J 0
(650 950);
DISPLAY 1.021277 (650 950);
DISPLAY INVISIBLE (650 950);
FORCEPROP 2 LAST $SEC 1
J 0
(650 950);
DISPLAY 0.680851 (650 950);
PAINT MONO (650 950);
DISPLAY INVISIBLE (650 950);
FORCEPROP 2 LAST CDS_SEC 1
J 0
(650 950);
DISPLAY 1.021277 (650 950);
DISPLAY INVISIBLE (650 950);
FORCEADD Q_RES..1
(700 625);
FORCEPROP 1 LAST PART_NUMBER CS12402FB01
J 0
(600 700);
DISPLAY 0.510638 (600 700);
DISPLAY INVISIBLE (600 700);
FORCEPROP 1 LAST VALUE 240
J 2
(900 625);
DISPLAY 0.638298 (900 625);
FORCEPROP 1 LAST TOLERANCE 1%
J 0
(925 625);
DISPLAY 0.638298 (925 625);
FORCEPROP 1 LAST MATERIAL EMPTY
J 0
(1025 625);
DISPLAY 0.638298 (1025 625);
FORCEPROP 1 LAST $LOCATION R1394
J 0
(475 625);
DISPLAY 0.638298 (475 625);
FORCEPROP 1 LASTPIN (600 625) $PN 1
J 0
(612 637);
DISPLAY 0.787234 (612 637);
FORCEPROP 1 LASTPIN (800 625) $PN 2
J 0
(762 637);
DISPLAY 0.787234 (762 637);
FORCEPROP 1 LAST PATH I67
J 0
(650 775);
DISPLAY 0.978723 (650 775);
PAINT WHITE (650 775);
DISPLAY INVISIBLE (650 775);
FORCEPROP 2 LAST CDS_LIB pure_quanta
J 0
(700 625);
PAINT MONO (700 625);
DISPLAY INVISIBLE (700 625);
FORCEPROP 1 LAST PACK_TYPE 0402LF
J 0
(600 725);
DISPLAY 0.510638 (600 725);
DISPLAY INVISIBLE (600 725);
FORCEPROP 1 LAST WATTAGE 1/16W
J 2
(875 725);
DISPLAY 0.510638 (875 725);
DISPLAY INVISIBLE (875 725);
FORCEPROP 2 LAST CDS_LOCATION R1394
J 0
(650 825);
DISPLAY 1.021277 (650 825);
DISPLAY INVISIBLE (650 825);
FORCEPROP 2 LAST $SEC 1
J 0
(650 825);
DISPLAY 0.680851 (650 825);
PAINT MONO (650 825);
DISPLAY INVISIBLE (650 825);
FORCEPROP 2 LAST CDS_SEC 1
J 0
(650 825);
DISPLAY 1.021277 (650 825);
DISPLAY INVISIBLE (650 825);
FORCEADD UNIVERSAL_POWER..1
(-2300 3650);
FORCEPROP 3 LASTPIN (-2300 3600) SIG_NAME PVNN_TERM_CPU0\g
J 0
(-2290 3610);
DISPLAY 0.659574 (-2290 3610);
PAINT MONO (-2290 3610);
DISPLAY INVISIBLE (-2290 3610);
FORCEPROP 1 LAST HDL_POWER PVNN_TERM_CPU0
J 1
(-2300 3700);
DISPLAY 0.872340 (-2300 3700);
PAINT GREEN (-2300 3700);
FORCEPROP 2 LAST CDS_LIB logical_power
J 0
(-2300 3650);
DISPLAY INVISIBLE (-2300 3650);
FORCEPROP 1 LAST PATH I8
J 0
(-2250 3675);
DISPLAY 0.872340 (-2250 3675);
PAINT AQUA (-2250 3675);
DISPLAY INVISIBLE (-2250 3675);
FORCEADD QUANTA_TITLE_BLOCK_C..1
(6150 -1925);
FORCEPROP 0 LAST CDS_CON_LAST_MODIFIED Fri Aug 25 14:01:40 2023
J 0
(4265 -1910);
PAINT MONO (4265 -1910);
DISPLAY INVISIBLE (4265 -1910);
FORCEPROP 1 LAST CUSTOM_TXT_CDS <CON_LAST_MODIFIED>
J 0
(4265 -1910);
DISPLAY 0.978723 (4265 -1910);
FORCEPROP 2 LAST CUSTOM_TXT_CDS <XR_PAGE_TITLE>
J 0
(-1740 3325);
DISPLAY 0.638298 (-1740 3325);
PAINT PINK (-1740 3325);
DISPLAY INVISIBLE (-1740 3325);
FORCEPROP 1 LAST CUSTOM_TXT_CDS <NAME_2>
J 0
(2975 -1875);
FORCEPROP 1 LAST CUSTOM_TXT_CDS <NAME_1>
J 0
(2975 -1750);
FORCEPROP 1 LAST CUSTOM_TXT_CDS <Q_NUMBER>
J 0
(4747 -1822);
DISPLAY 1.212766 (4747 -1822);
FORCEPROP 1 LAST CUSTOM_TXT_CDS <Q_PROJ>
J 0
(3768 -1823);
DISPLAY 1.212766 (3768 -1823);
FORCEPROP 1 LAST CUSTOM_TXT_CDS <Q_REV>
J 0
(5966 -1822);
DISPLAY 1.212766 (5966 -1822);
FORCEPROP 1 LAST CUSTOM_TXT_CDS <CON_PAGE_NUM> OF <CON_TOTAL_PAGES>
J 0
(5704 -1907);
DISPLAY 0.978723 (5704 -1907);
FORCEPROP 1 LAST Q_TITLE SPR CPU0 & 1 SIDE BAND-GPIO
J 0
(-3116 -1924);
DISPLAY 2.446809 (-3116 -1924);
PAINT GREEN (-3116 -1924);
FORCEPROP 1 LAST Q_DEPT 
J 1
(2387 -1876);
DISPLAY 1.957447 (2387 -1876);
PAINT GREEN (2387 -1876);
FORCEPROP 2 LAST CDS_XR_PAGE_TITLE CR-120 : @S9S_MB_2U_LIB.S9S_MB_2U(SCH_1):PAGE120
J 0
(-1740 3325);
DISPLAY 0.638298 (-1740 3325);
PAINT PINK (-1740 3325);
DISPLAY INVISIBLE (-1740 3325);
FORCEPROP 1 LAST COMMENT_BODY TRUE
J 0
(6162 -1938);
DISPLAY 0.978723 (6162 -1938);
PAINT GREEN (6162 -1938);
DISPLAY INVISIBLE (6162 -1938);
FORCEPROP 2 LAST CDS_LIB pure_quanta
J 0
(6150 -1925);
PAINT MONO (6150 -1925);
DISPLAY INVISIBLE (6150 -1925);
FORCEPROP 1 LAST CDS_LMAN_SYM_OUTLINE -9475,6775,100,-125
J 0
(6150 -1925);
DISPLAY 0.468085 (6150 -1925);
PAINT GREEN (6150 -1925);
DISPLAY INVISIBLE (6150 -1925);
FORCEPROP 2 LAST PAGE_BORDER TRUE
J 0
(-1740 3325);
DISPLAY 0.638298 (-1740 3325);
PAINT PINK (-1740 3325);
DISPLAY INVISIBLE (-1740 3325);
FORCEADD DNS..2
(700 3175);
PAINT RED (700 3175);
FORCEPROP 2 LAST CDS_LIB mstr_misc
J 0
(700 3175);
DISPLAY INVISIBLE (700 3175);
FORCEPROP 1 LAST COMMENT_BODY TRUE
R 1
J 0
(775 2950);
DISPLAY 0.872340 (775 2950);
PAINT GREEN (775 2950);
DISPLAY INVISIBLE (775 2950);
FORCEADD DNS..2
(700 3050);
PAINT RED (700 3050);
FORCEPROP 2 LAST CDS_LIB mstr_misc
J 0
(700 3050);
DISPLAY INVISIBLE (700 3050);
FORCEPROP 1 LAST COMMENT_BODY TRUE
R 1
J 0
(775 2825);
DISPLAY 0.872340 (775 2825);
PAINT GREEN (775 2825);
DISPLAY INVISIBLE (775 2825);
FORCEADD DNS..2
(-1975 3275);
PAINT RED (-1975 3275);
FORCEPROP 2 LAST CDS_LIB mstr_misc
J 0
(-1975 3275);
PAINT MONO (-1975 3275);
DISPLAY INVISIBLE (-1975 3275);
FORCEPROP 1 LAST COMMENT_BODY TRUE
R 1
J 0
(-1900 3050);
DISPLAY 0.872340 (-1900 3050);
PAINT GREEN (-1900 3050);
DISPLAY INVISIBLE (-1900 3050);
FORCEADD DNS..2
(-1975 900);
PAINT RED (-1975 900);
FORCEPROP 2 LAST CDS_LIB mstr_misc
J 0
(-1975 900);
PAINT MONO (-1975 900);
DISPLAY INVISIBLE (-1975 900);
FORCEPROP 1 LAST COMMENT_BODY TRUE
R 1
J 0
(-1900 675);
DISPLAY 0.872340 (-1900 675);
PAINT GREEN (-1900 675);
DISPLAY INVISIBLE (-1900 675);
FORCEADD DNS..2
(-1975 3400);
PAINT RED (-1975 3400);
FORCEPROP 2 LAST CDS_LIB mstr_misc
J 0
(-1975 3400);
PAINT MONO (-1975 3400);
DISPLAY INVISIBLE (-1975 3400);
FORCEPROP 1 LAST COMMENT_BODY TRUE
R 1
J 0
(-1900 3175);
DISPLAY 0.872340 (-1900 3175);
PAINT GREEN (-1900 3175);
DISPLAY INVISIBLE (-1900 3175);
FORCEADD DNS..2
(-1975 775);
PAINT RED (-1975 775);
FORCEPROP 2 LAST CDS_LIB mstr_misc
J 0
(-1975 775);
PAINT MONO (-1975 775);
DISPLAY INVISIBLE (-1975 775);
FORCEPROP 1 LAST COMMENT_BODY TRUE
R 1
J 0
(-1900 550);
DISPLAY 0.872340 (-1900 550);
PAINT GREEN (-1900 550);
DISPLAY INVISIBLE (-1900 550);
FORCEADD DNS..2
(-1975 2900);
PAINT RED (-1975 2900);
FORCEPROP 2 LAST CDS_LIB mstr_misc
J 0
(-1975 2900);
PAINT MONO (-1975 2900);
DISPLAY INVISIBLE (-1975 2900);
FORCEPROP 1 LAST COMMENT_BODY TRUE
R 1
J 0
(-1900 2675);
DISPLAY 0.872340 (-1900 2675);
PAINT GREEN (-1900 2675);
DISPLAY INVISIBLE (-1900 2675);
FORCEADD DNS..2
(-1975 400);
PAINT RED (-1975 400);
FORCEPROP 1 LAST COMMENT_BODY TRUE
R 1
J 0
(-1900 175);
DISPLAY 0.872340 (-1900 175);
PAINT GREEN (-1900 175);
DISPLAY INVISIBLE (-1900 175);
FORCEPROP 2 LAST CDS_LIB mstr_misc
J 0
(-1975 400);
PAINT MONO (-1975 400);
DISPLAY INVISIBLE (-1975 400);
FORCEADD DNS..2
(725 750);
PAINT RED (725 750);
FORCEPROP 2 LAST CDS_LIB mstr_misc
J 0
(725 750);
DISPLAY INVISIBLE (725 750);
FORCEPROP 1 LAST COMMENT_BODY TRUE
R 1
J 0
(800 525);
DISPLAY 0.872340 (800 525);
PAINT GREEN (800 525);
DISPLAY INVISIBLE (800 525);
FORCEADD DNS..2
(725 625);
PAINT RED (725 625);
FORCEPROP 2 LAST CDS_LIB mstr_misc
J 0
(725 625);
DISPLAY INVISIBLE (725 625);
FORCEPROP 1 LAST COMMENT_BODY TRUE
R 1
J 0
(800 400);
DISPLAY 0.872340 (800 400);
PAINT GREEN (800 400);
DISPLAY INVISIBLE (800 400);
WIRE 16 -1 (-2300 3600)(-2300 3400);
WIRE 16 -1 (-2300 1100)(-2300 900);
WIRE 16 -1 (400 3075)(400 2975);
WIRE 16 -1 (400 3200)(400 3075);
WIRE 16 -1 (400 3075)(600 3075);
WIRE 16 -1 (400 625)(400 525);
WIRE 16 -1 (400 750)(400 625);
WIRE 16 -1 (400 625)(600 625);
WIRE 16 -1 (-2300 3400)(-2100 3400);
WIRE 16 -1 (-2300 3275)(-2100 3275);
WIRE 16 -1 (-2300 3400)(-2300 3275);
WIRE 16 -1 (-2300 2900)(-2100 2900);
WIRE 16 -1 (-2300 3275)(-2300 2900);
WIRE 16 -1 (-2300 2775)(-2100 2775);
WIRE 16 -1 (-2300 2900)(-2300 2775);
WIRE 16 -1 (-2300 2775)(-2300 2650);
WIRE 16 -1 (-2300 2650)(-2100 2650);
WIRE 16 -1 (-2300 2525)(-2100 2525);
WIRE 16 -1 (-2300 2525)(-2300 2650);
WIRE 16 -1 (400 750)(600 750);
WIRE 16 -1 (400 3200)(600 3200);
WIRE 16 -1 (-2300 900)(-2100 900);
WIRE 16 -1 (-2300 900)(-2300 775);
WIRE 16 -1 (-2300 775)(-2100 775);
WIRE 16 -1 (-2300 400)(-2100 400);
WIRE 16 -1 (-2300 775)(-2300 400);
WIRE 16 -1 (-2300 400)(-2300 275);
WIRE 16 -1 (-2300 275)(-2100 275);
WIRE 16 -1 (-2300 150)(-2100 150);
WIRE 16 -1 (-2300 275)(-2300 150);
WIRE 16 -1 (-2300 25)(-2300 150);
WIRE 16 -1 (-2300 25)(-2100 25);
WIRE 16 -1 (-1900 775)(-550 775);
FORCEPROP 2 LAST SIG_NAME FM_S3M_CPU1_LVC1_GPIO_1
J 0
(-1400 785);
DISPLAY 0.680851 (-1400 785);
PAINT WHITE (-1400 785);
WIRE 16 2175 (425 550)(1175 550);
WIRE 16 2175 (1175 900)(1175 550);
WIRE 16 2175 (425 900)(425 550);
WIRE 16 2175 (425 900)(1175 900);
WIRE 16 -1 (800 625)(2150 625);
FORCEPROP 2 LAST SIG_NAME FM_S3M_CPU1_LVC1_GPIO_3
J 0
(1300 635);
DISPLAY 0.680851 (1300 635);
PAINT WHITE (1300 635);
WIRE 16 -1 (-1900 400)(-550 400);
FORCEPROP 2 LAST SIG_NAME FM_S3M_CPU1_LVC1_GPIO_4
J 0
(-1400 410);
DISPLAY 0.680851 (-1400 410);
PAINT WHITE (-1400 410);
WIRE 16 2175 (-2250 -75)(-1525 -75);
WIRE 16 2175 (-1525 225)(-1525 -75);
WIRE 16 2175 (-2250 225)(-2250 -75);
WIRE 16 2175 (-2250 225)(-1525 225);
WIRE 16 -1 (-1900 25)(-550 25);
FORCEPROP 2 LAST SIG_NAME FM_S3M_CPU1_LVC1_GPIO_3
J 0
(-1400 35);
DISPLAY 0.680851 (-1400 35);
PAINT WHITE (-1400 35);
WIRE 16 2175 (425 2975)(1150 2975);
WIRE 16 2175 (1150 3325)(1150 2975);
WIRE 16 2175 (425 3325)(425 2975);
WIRE 16 2175 (425 3325)(1150 3325);
WIRE 16 -1 (800 3075)(2150 3075);
FORCEPROP 2 LAST SIG_NAME FM_S3M_CPU0_LVC1_GPIO_3
J 0
(1300 3085);
DISPLAY 0.680851 (1300 3085);
PAINT WHITE (1300 3085);
WIRE 16 -1 (800 3200)(2150 3200);
FORCEPROP 2 LAST SIG_NAME FM_S3M_CPU0_LVC1_GPIO_2
J 0
(1300 3210);
DISPLAY 0.680851 (1300 3210);
PAINT WHITE (1300 3210);
WIRE 16 -1 (-1900 2525)(-550 2525);
FORCEPROP 2 LAST SIG_NAME FM_S3M_CPU0_LVC1_GPIO_3
J 0
(-1400 2535);
DISPLAY 0.680851 (-1400 2535);
PAINT WHITE (-1400 2535);
WIRE 16 2175 (-2275 2400)(-1550 2400);
WIRE 16 2175 (-1550 2750)(-1550 2400);
WIRE 16 2175 (-2275 2750)(-2275 2400);
WIRE 16 2175 (-2275 2750)(-1550 2750);
WIRE 16 -1 (-1900 2650)(-550 2650);
FORCEPROP 2 LAST SIG_NAME FM_S3M_CPU0_LVC1_GPIO_2
J 0
(-1400 2660);
DISPLAY 0.680851 (-1400 2660);
PAINT WHITE (-1400 2660);
WIRE 16 -1 (-1900 150)(-550 150);
FORCEPROP 2 LAST SIG_NAME FM_S3M_CPU1_LVC1_GPIO_2
J 0
(-1400 160);
DISPLAY 0.680851 (-1400 160);
PAINT WHITE (-1400 160);
WIRE 16 -1 (-1900 275)(-550 275);
FORCEPROP 2 LAST SIG_NAME PUD_PCH_BOOT_MODE_CPU1
J 0
(-1400 285);
DISPLAY 0.680851 (-1400 285);
PAINT WHITE (-1400 285);
WIRE 16 -1 (800 750)(2150 750);
FORCEPROP 2 LAST SIG_NAME FM_S3M_CPU1_LVC1_GPIO_2
J 0
(1300 760);
DISPLAY 0.680851 (1300 760);
PAINT WHITE (1300 760);
WIRE 16 -1 (-1900 2775)(-550 2775);
FORCEPROP 2 LAST SIG_NAME PUD_PCH_BOOT_MODE_CPU0
J 0
(-1400 2785);
DISPLAY 0.680851 (-1400 2785);
PAINT WHITE (-1400 2785);
WIRE 16 273 (3450 2650)(3450 1700);
WIRE 16 273 (3450 2650)(3975 2650);
WIRE 16 273 (3975 2650)(3975 1700);
WIRE 16 273 (3450 1700)(3975 1700);
WIRE 16 273 (3975 1700)(5975 1700);
WIRE 16 273 (3975 2650)(5975 2650);
WIRE 16 273 (2950 1700)(3450 1700);
WIRE 16 273 (2950 2650)(3450 2650);
WIRE 16 273 (2950 2650)(2950 2450);
WIRE 16 273 (2950 1950)(2950 1700);
WIRE 16 273 (5975 2450)(5975 2650);
WIRE 16 273 (2950 2450)(5975 2450);
WIRE 16 273 (5975 1700)(5975 1950);
WIRE 16 273 (2950 1950)(5975 1950);
WIRE 16 273 (5975 1950)(5975 2200);
WIRE 16 273 (5975 2200)(5975 2450);
WIRE 16 273 (2950 2200)(2950 1950);
WIRE 16 273 (2950 2450)(2950 2200);
WIRE 16 273 (2950 2200)(5975 2200);
WIRE 16 -1 (-1900 2900)(-550 2900);
FORCEPROP 2 LAST SIG_NAME FM_S3M_CPU0_LVC1_GPIO_4
J 0
(-1400 2910);
DISPLAY 0.680851 (-1400 2910);
PAINT WHITE (-1400 2910);
WIRE 16 -1 (-1900 900)(-550 900);
FORCEPROP 2 LAST SIG_NAME FM_S3M_CPU1_LVC1_GPIO_0
J 0
(-1400 910);
DISPLAY 0.680851 (-1400 910);
PAINT WHITE (-1400 910);
WIRE 16 -1 (-1900 3275)(-550 3275);
FORCEPROP 2 LAST SIG_NAME FM_S3M_CPU0_LVC1_GPIO_1
J 0
(-1400 3285);
DISPLAY 0.680851 (-1400 3285);
PAINT WHITE (-1400 3285);
WIRE 16 -1 (-1900 3400)(-550 3400);
FORCEPROP 2 LAST SIG_NAME FM_S3M_CPU0_LVC1_GPIO_0
J 0
(-1400 3410);
DISPLAY 0.680851 (-1400 3410);
PAINT WHITE (-1400 3410);
DOT 1 (400 3075);
DOT 1 (-2300 2650);
DOT 1 (-2300 275);
DOT 1 (3450 1700);
DOT 1 (3975 1700);
DOT 1 (-2300 3400);
DOT 1 (3450 2650);
DOT 1 (3975 2650);
DOT 1 (2950 2200);
DOT 1 (2950 1950);
DOT 1 (2950 2450);
DOT 1 (5975 2450);
DOT 1 (5975 2200);
DOT 1 (5975 1950);
DOT 1 (-2300 400);
DOT 1 (-2300 2900);
DOT 1 (-2300 900);
DOT 1 (-2300 3275);
DOT 1 (-2300 775);
DOT 1 (-2300 2775);
DOT 1 (-2300 150);
DOT 1 (400 625);
FORCENOTE
20211126 DEPOP R259,R260
(-2225 -250) 0;
DISPLAY LEFT (-2225 -250);
DISPLAY 1.680851 (-2225 -250);
PAINT WHITE (-2225 -250);
FORCENOTE
20221028 DEPOP R1393,R1394
(550 275) 0;
DISPLAY LEFT (550 275);
DISPLAY 1.680851 (550 275);
PAINT WHITE (550 275);
FORCENOTE
20211126 POP R1393,R1394
(550 400) 0;
DISPLAY LEFT (550 400);
DISPLAY 1.680851 (550 400);
PAINT WHITE (550 400);
FORCENOTE
20221028 DEPOP R1391,R1392
(500 2675) 0;
DISPLAY LEFT (500 2675);
DISPLAY 1.680851 (500 2675);
PAINT WHITE (500 2675);
FORCENOTE
20211126 POP R1391,R1392
(500 2800) 0;
DISPLAY LEFT (500 2800);
DISPLAY 1.680851 (500 2800);
PAINT WHITE (500 2800);
FORCENOTE
20211126 DEPOP R253,R254
(-2275 2275) 0;
DISPLAY LEFT (-2275 2275);
DISPLAY 1.680851 (-2275 2275);
PAINT WHITE (-2275 2275);
FORCENOTE
20221028 POP R253,R254
(-2275 2175) 0;
DISPLAY LEFT (-2275 2175);
DISPLAY 1.680851 (-2275 2175);
PAINT WHITE (-2275 2175);
FORCENOTE
20221028 POP R259,R260
(-2225 -350) 0;
DISPLAY LEFT (-2225 -350);
DISPLAY 1.680851 (-2225 -350);
PAINT WHITE (-2225 -350);
FORCENOTE
0: PCH BOOT MODE
(4075 1750) 0;
DISPLAY LEFT (4075 1750);
DISPLAY 1.021277 (4075 1750);
PAINT WHITE (4075 1750);
FORCENOTE
PD
(3650 1800) 0;
DISPLAY LEFT (3650 1800);
DISPLAY 1.021277 (3650 1800);
PAINT WHITE (3650 1800);
FORCENOTE
GPIO4
(3000 1800) 0;
DISPLAY LEFT (3000 1800);
DISPLAY 1.021277 (3000 1800);
PAINT WHITE (3000 1800);
FORCENOTE
CPU1 S3M STRAPS
(-2300 1550) 0;
DISPLAY LEFT (-2300 1550);
DISPLAY 4.127660 (-2300 1550);
PAINT WHITE (-2300 1550);
FORCENOTE
DESCRIPTION
(4575 2525) 0;
DISPLAY LEFT (4575 2525);
DISPLAY 1.021277 (4575 2525);
PAINT WHITE (4575 2525);
FORCENOTE
PD: SPR XCC
(4075 2075) 0;
DISPLAY LEFT (4075 2075);
DISPLAY 1.021277 (4075 2075);
PAINT WHITE (4075 2075);
FORCENOTE
GPIO0/1
(3000 2300) 0;
DISPLAY LEFT (3000 2300);
DISPLAY 1.021277 (3000 2300);
PAINT WHITE (3000 2300);
FORCENOTE
SPR GPIO
(3000 2525) 0;
DISPLAY LEFT (3000 2525);
DISPLAY 1.021277 (3000 2525);
PAINT WHITE (3000 2525);
FORCENOTE
INTERNAL
(3525 2550) 0;
DISPLAY LEFT (3525 2550);
DISPLAY 1.021277 (3525 2550);
PAINT WHITE (3525 2550);
FORCENOTE
GPIO2/3
(3000 2050) 0;
DISPLAY LEFT (3000 2050);
DISPLAY 1.021277 (3000 2050);
PAINT WHITE (3000 2050);
FORCENOTE
1: CPU BOOT MODE
(4075 1800) 0;
DISPLAY LEFT (4075 1800);
DISPLAY 1.021277 (4075 1800);
PAINT WHITE (4075 1800);
FORCENOTE
PD
(3650 2050) 0;
DISPLAY LEFT (3650 2050);
DISPLAY 1.021277 (3650 2050);
PAINT WHITE (3650 2050);
FORCENOTE
1: BIST ENABLED
(4075 2325) 0;
DISPLAY LEFT (4075 2325);
DISPLAY 1.021277 (4075 2325);
PAINT WHITE (4075 2325);
FORCENOTE
BOOT MODE
(4075 1875) 0;
DISPLAY LEFT (4075 1875);
DISPLAY 1.021277 (4075 1875);
PAINT WHITE (4075 1875);
FORCENOTE
PU
(3650 2300) 0;
DISPLAY LEFT (3650 2300);
DISPLAY 1.021277 (3650 2300);
PAINT WHITE (3650 2300);
FORCENOTE
PU/PD
(3525 2475) 0;
DISPLAY LEFT (3525 2475);
DISPLAY 1.021277 (3525 2475);
PAINT WHITE (3525 2475);
FORCENOTE
0: BIST DISABLED
(4075 2275) 0;
DISPLAY LEFT (4075 2275);
DISPLAY 1.021277 (4075 2275);
PAINT WHITE (4075 2275);
FORCENOTE
PU: SPR HCC
(4075 2025) 0;
DISPLAY LEFT (4075 2025);
DISPLAY 1.021277 (4075 2025);
PAINT WHITE (4075 2025);
FORCENOTE
CPU0 S3M STRAPS
(-2300 4050) 0;
DISPLAY LEFT (-2300 4050);
DISPLAY 4.127660 (-2300 4050);
PAINT WHITE (-2300 4050);
QUIT
